# S9S_MB_2U (Grand Teton) — schematic netlist excerpt (pin names and nets, part order shuffled) for the footprints in the layout excerpt that follows; sources: Cadence DE-HDL packaged netlist, KiCad conversion of 03242023_DA0F0TMBIJ0_F0T_Motherboard_J_brd_V01_OCP.brd

R821  Q_RES  1K 1% CHIP  pkg 0402LF  page 130 : A = PVCCD_HV_CPU1 ; B = RST_M_CD_CPU1_FPGA_N
C1838  Q_CAP  0.1UF 25V 10% X7R  pkg 0402  page 159 : A = P3V3_OCP_V3_2 ; B = GND

(kicad_pcb
	(version 20260206)
	(generator "pcbnew")
	(generator_version "10.0")
	(general
		(thickness 1.6)
		(legacy_teardrops no)
	)
	(paper "A4")
	(title_block
		(title "03242023_DA0F0TMBIJ0_F0T_Motherboard_J_brd_V01_OCP.brd")
		(comment 1 "Grand Teton / footprints 5998-5999 of 6105")
	)
	(layers
		(0 "F.Cu" signal "TOP")
		(4 "In1.Cu" signal "GND")
		(6 "In2.Cu" signal "IN1")
		(8 "In3.Cu" signal "GND1")
		(10 "In4.Cu" signal "IN2")
		(12 "In5.Cu" signal "GND2")
		(14 "In6.Cu" signal "IN3")
		(16 "In7.Cu" signal "GND3")
		(18 "In8.Cu" signal "VCC")
		(20 "In9.Cu" signal "VCC1")
		(22 "In10.Cu" signal "GND4")
		(24 "In11.Cu" signal "IN4")
		(26 "In12.Cu" signal "GND5")
		(28 "In13.Cu" signal "IN5")
		(30 "In14.Cu" signal "GND6")
		(32 "In15.Cu" signal "IN6")
		(34 "In16.Cu" signal "GND7")
		(2 "B.Cu" signal "BOTTOM")
		(9 "F.Adhes" user "F.Adhesive")
		(11 "B.Adhes" user "B.Adhesive")
		(13 "F.Paste" user "Package Geometry/Pastemask Top")
		(15 "B.Paste" user "Package Geometry/Pastemask Bottom")
		(5 "F.SilkS" user "Ref Des/Silkscreen Top")
		(7 "B.SilkS" user "Ref Des/Silkscreen Bottom")
		(1 "F.Mask" user "Board Geometry/Soldermask Top")
		(3 "B.Mask" user "Board Geometry/Soldermask Bottom")
		(17 "Dwgs.User" user "User.Drawings")
		(19 "Cmts.User" user "User.Comments")
		(21 "Eco1.User" user "User.Eco1")
		(23 "Eco2.User" user "User.Eco2")
		(25 "Edge.Cuts" user "Board Geometry/Outline")
		(27 "Margin" user)
		(31 "F.CrtYd" user "Package Geometry/Place Bound Top")
		(29 "B.CrtYd" user "Package Geometry/Place Bound Bottom")
		(35 "F.Fab" user "Ref Des/Assembly Top")
		(33 "B.Fab" user "Ref Des/Assembly Bottom")
	)
	(footprint ""
		(layer "B.Cu")
		(at 27.375866 -193.152776 -90)
		(property "Reference" "R821"
			(at 0 0 90)
			(layer "B.SilkS")
			(hide yes)
			(effects
				(font
					(size 1.27 1.27)
				)
				(justify mirror)
			)
		)
		(property "Value" ""
			(at 0 0 90)
			(layer "B.Fab")
			(effects
				(font
					(size 1.27 1.27)
				)
				(justify mirror)
			)
		)
		(duplicate_pad_numbers_are_jumpers no)
		(fp_line
			(start -0.7874 0.4064)
			(end 0.7874 0.4064)
			(stroke
				(width 0.1524)
				(type default)
			)
			(layer "B.SilkS")
		)
		(fp_line
			(start 0.7874 0.4064)
			(end 0.7874 -0.4064)
			(stroke
				(width 0.1524)
				(type default)
			)
			(layer "B.SilkS")
		)
		(fp_line
			(start -0.7874 -0.4064)
			(end -0.7874 0.4064)
			(stroke
				(width 0.1524)
				(type default)
			)
			(layer "B.SilkS")
		)
		(fp_line
			(start 0.7874 -0.4064)
			(end -0.7874 -0.4064)
			(stroke
				(width 0.1524)
				(type default)
			)
			(layer "B.SilkS")
		)
		(fp_line
			(start -0.67945 0.3048)
			(end -0.120396 0.3048)
			(stroke
				(width 0.1)
				(type default)
			)
			(layer "B.Fab")
		)
		(fp_line
			(start -0.120396 0.3048)
			(end -0.120396 0.2794)
			(stroke
				(width 0.1)
				(type default)
			)
			(layer "B.Fab")
		)
		(fp_line
			(start 0.12065 0.3048)
			(end 0.67945 0.3048)
			(stroke
				(width 0.1)
				(type default)
			)
			(layer "B.Fab")
		)
		(fp_line
			(start 0.67945 0.3048)
			(end 0.67945 -0.305054)
			(stroke
				(width 0.1)
				(type default)
			)
			(layer "B.Fab")
		)
		(fp_line
			(start -0.120396 0.2794)
			(end 0.12065 0.2794)
			(stroke
				(width 0.1)
				(type default)
			)
			(layer "B.Fab")
		)
		(fp_line
			(start 0.12065 0.2794)
			(end 0.12065 0.3048)
			(stroke
				(width 0.1)
				(type default)
			)
			(layer "B.Fab")
		)
		(fp_line
			(start -0.12065 -0.2794)
			(end -0.12065 -0.3048)
			(stroke
				(width 0.1)
				(type default)
			)
			(layer "B.Fab")
		)
		(fp_line
			(start 0.12065 -0.2794)
			(end -0.12065 -0.2794)
			(stroke
				(width 0.1)
				(type default)
			)
			(layer "B.Fab")
		)
		(fp_line
			(start -0.67945 -0.3048)
			(end -0.67945 0.3048)
			(stroke
				(width 0.1)
				(type default)
			)
			(layer "B.Fab")
		)
		(fp_line
			(start -0.12065 -0.3048)
			(end -0.67945 -0.3048)
			(stroke
				(width 0.1)
				(type default)
			)
			(layer "B.Fab")
		)
		(fp_line
			(start 0.12065 -0.305054)
			(end 0.12065 -0.2794)
			(stroke
				(width 0.1)
				(type default)
			)
			(layer "B.Fab")
		)
		(fp_line
			(start 0.67945 -0.305054)
			(end 0.12065 -0.305054)
			(stroke
				(width 0.1)
				(type default)
			)
			(layer "B.Fab")
		)
		(pad "1" smd circle
			(at 0.40005 0 90)
			(size 0 0)
			(layers "B.Cu" "B.Mask" "B.Paste")
			(net "PVCCD_HV_CPU1")
		)
		(pad "2" smd circle
			(at -0.40005 0 90)
			(size 0 0)
			(layers "B.Cu" "B.Mask" "B.Paste")
			(net "RST_M_CD_CPU1_FPGA_N")
		)
	)
	(footprint ""
		(layer "B.Cu")
		(at 63.55588 -8.981948 90)
		(property "Reference" "C1838"
			(at 0 0 90)
			(layer "B.SilkS")
			(hide yes)
			(effects
				(font
					(size 1.27 1.27)
				)
				(justify mirror)
			)
		)
		(property "Value" ""
			(at 0 0 90)
			(layer "B.Fab")
			(effects
				(font
					(size 1.27 1.27)
				)
				(justify mirror)
			)
		)
		(duplicate_pad_numbers_are_jumpers no)
		(fp_line
			(start 0.7874 -0.4064)
			(end -0.7874 -0.4064)
			(stroke
				(width 0.1524)
				(type default)
			)
			(layer "B.SilkS")
		)
		(fp_line
			(start -0.7874 -0.4064)
			(end -0.7874 0.4064)
			(stroke
				(width 0.1524)
				(type default)
			)
			(layer "B.SilkS")
		)
		(fp_line
			(start 0.7874 0.4064)
			(end 0.7874 -0.4064)
			(stroke
				(width 0.1524)
				(type default)
			)
			(layer "B.SilkS")
		)
		(fp_line
			(start -0.7874 0.4064)
			(end 0.7874 0.4064)
			(stroke
				(width 0.1524)
				(type default)
			)
			(layer "B.SilkS")
		)
		(fp_line
			(start 0.67945 -0.305054)
			(end 0.12065 -0.305054)
			(stroke
				(width 0.1)
				(type default)
			)
			(layer "B.Fab")
		)
		(fp_line
			(start 0.12065 -0.305054)
			(end 0.12065 -0.2794)
			(stroke
				(width 0.1)
				(type default)
			)
			(layer "B.Fab")
		)
		(fp_line
			(start -0.12065 -0.3048)
			(end -0.67945 -0.3048)
			(stroke
				(width 0.1)
				(type default)
			)
			(layer "B.Fab")
		)
		(fp_line
			(start -0.67945 -0.3048)
			(end -0.67945 0.3048)
			(stroke
				(width 0.1)
				(type default)
			)
			(layer "B.Fab")
		)
		(fp_line
			(start 0.12065 -0.2794)
			(end -0.12065 -0.2794)
			(stroke
				(width 0.1)
				(type default)
			)
			(layer "B.Fab")
		)
		(fp_line
			(start -0.12065 -0.2794)
			(end -0.12065 -0.3048)
			(stroke
				(width 0.1)
				(type default)
			)
			(layer "B.Fab")
		)
		(fp_line
			(start 0.12065 0.2794)
			(end 0.12065 0.3048)
			(stroke
				(width 0.1)
				(type default)
			)
			(layer "B.Fab")
		)
		(fp_line
			(start -0.120396 0.2794)
			(end 0.12065 0.2794)
			(stroke
				(width 0.1)
				(type default)
			)
			(layer "B.Fab")
		)
		(fp_line
			(start 0.67945 0.3048)
			(end 0.67945 -0.305054)
			(stroke
				(width 0.1)
				(type default)
			)
			(layer "B.Fab")
		)
		(fp_line
			(start 0.12065 0.3048)
			(end 0.67945 0.3048)
			(stroke
				(width 0.1)
				(type default)
			)
			(layer "B.Fab")
		)
		(fp_line
			(start -0.120396 0.3048)
			(end -0.120396 0.2794)
			(stroke
				(width 0.1)
				(type default)
			)
			(layer "B.Fab")
		)
		(fp_line
			(start -0.67945 0.3048)
			(end -0.120396 0.3048)
			(stroke
				(width 0.1)
				(type default)
			)
			(layer "B.Fab")
		)
		(pad "1" smd circle
			(at 0.40005 0 270)
			(size 0 0)
			(layers "B.Cu" "B.Mask" "B.Paste")
			(net "P3V3_OCP_V3_2")
		)
		(pad "2" smd circle
			(at -0.40005 0 270)
			(size 0 0)
			(layers "B.Cu" "B.Mask" "B.Paste")
			(net "GND")
		)
	)
)
